#ISCELL
  mstr_symbols intel_corp_bpage *
  *
#CELL
  w_hdl test-pad-12p-1-gp-u *
  page272_i1
#ISCELL
  mstr_symbols gnd *
  page272_i10
#ISCELL
  mstr_symbols gnd *
  page272_i11
#CELL
  w_hdl test-pad-12p-1-gp-u *
  page272_i12
#ISCELL
  mstr_symbols gnd *
  page272_i13
#CELL
  w_hdl test-pad-12p-1-gp-u *
  page272_i14
#ISCELL
  mstr_symbols gnd *
  page272_i15
#CELL
  w_hdl test-pad-12p-1-gp-u *
  page272_i16
#ISCELL
  mstr_symbols gnd *
  page272_i17
#ISCELL
  mstr_symbols gnd *
  page272_i18
#ISCELL
  mstr_symbols gnd *
  page272_i19
#ISCELL
  mstr_symbols gnd *
  page272_i2
#ISCELL
  mstr_symbols gnd *
  page272_i20
#CELL
  w_hdl test-pad-12p-1-gp-u *
  page272_i21
#CELL
  w_hdl test-pad-12p-1-gp-u *
  page272_i22
#CELL
  w_hdl test-pad-12p-1-gp-u *
  page272_i23
#CELL
  w_hdl test-pad-12p-1-gp-u *
  page272_i24
#CELL
  w_hdl test-pad-12p-1-gp-u *
  page272_i3
#ISCELL
  mstr_symbols gnd *
  page272_i4
#CELL
  w_hdl test-pad-12p-1-gp-u *
  page272_i5
#ISCELL
  mstr_symbols gnd *
  page272_i6
#ISCELL
  mstr_symbols gnd *
  page272_i7
#CELL
  w_hdl test-pad-12p-1-gp-u *
  page272_i8
#CELL
  w_hdl test-pad-12p-1-gp-u *
  page272_i9
